FILE_TYPE = CONNECTIVITY;
{Allegro Design Entry HDL 16.6-p007 (v16-6-112F) 10/10/2012}
"PAGE_NUMBER" = 119;
0"NC";
1"P3V3_STBY\g";
2"GND\g";
3"P3V3_STBY\g";
4"GND\g";
5"P3V3_STBY\g";
6"P3V3_STBY\g";
7"FM_QAT_EN_N";
8"FM_PWR_BTN_N";
9"FM_PMBUS_ALERT_BUF_EN_N";
10"FM_BIOS_TOP_SWAP_SPKR";
11"FM_PCH_PWRBTN_OUT_N";
12"FM_UV_ADR_TRIGGER_EN";
13"FM_BIOS_PREFRB2_GOOD";
14"FM_BIOS_POST_CMPLT_N";
15"FM_FAST_PROCHOT_EN_N";
16"FM_USB_P0_EN_BOOT_BIOS_STRAP_N";
17"PU_FM_RCIN_N";
18"LPC_LAD1_IO1";
19"LPC_LAD3_IO3";
20"PU_LPC_PME_N";
21"FM_MB_SLOT_ID2";
22"FM_BMC_READY_N";
23"FM_SLT_CFG2_R";
24"FM_BIOS_POST_CMPLT_N";
25"FM_SLT_CFG1";
26"FM_PCH_SATA_RAID_KEY";
27"SMB_SMLINK0_STBY_LVC3_SDA_R1";
28"SMB_SMLINK0_STBY_LVC3_SCL_R1";
29"FM_TPM_PRES_N";
30"FM_OCP_MEZZA_PRES_N";
31"FM_POST_CARD_PRES_BMC_N";
32"RST_PCH_SYSRST_BTN_OUT_N";
33"LPC_LFRAME_N_CS0_N";
34"FM_PCH_BMC_THERMTRIP_EXI_STRAP_N";
35"IRQ_PCH_NIC_ALERT_N";
36"PU_IRQ_VRALERT_N";
37"FM_CPU_CATERR_DLY_LVT3_N";
38"FM_PWRBRK_SLOT_N";
39"FM_CPU_CATERR_DLY_LVT3_R_N";
40"FM_THROTTLE_N";
41"FM_BB_BMC_MP_GPIO";
42"FM_PMBUS_ALERT_BUF_EN_N";
43"IRQ_BMC_PCH_SMI_LPC_N";
44"FM_PCH_PLD_DATA";
45"FM_ADR_MODE_SEL";
46"FM_PWR_LED_A";
47"FM_PWR_LED_K";
48"FM_PWR_LED";
49"TP_PCH_GPP_D12";
50"FM_PCH_PLD_DATA_R";
51"SMB_SLOTX24_STBY_LVC3_SCL_R1";
52"IRQ_BMC_PCH_NMI_STBY_R_N";
53"SMB_SLOTX24_STBY_LVC3_SDA_R1";
54"FM_BOARD_REV_ID0";
55"FM_SLT_CFG0";
56"FM_CPLD_BMC_PWRDN_N";
57"FM_PWR_LED_N";
58"IRQ_OOB_MGMT_RISER_ALERT_N";
59"IRQ_LOM_ALERT_N";
60"FM_BMC_CPLD_GPO";
61"SGPIO_PCH_SSATA_DOUT0";
62"IRQ_FORCE_NM_THROTTLE_N";
63"FM_BMC_FAULT_LED_N";
64"H_CPU0_FAST_WAKE_LVT3_N";
65"FM_BMC_ENABLE_N";
66"IRQ_MEZZ_LAN_ALERT_N";
67"IRQ_HSC_FAULT_N";
68"FM_XRC_PRESENT_N";
69"FM_CPU0_THERMTRIP_LATCH_LVT3_N";
70"SP2_BMC_CM_UART_TX";
71"SP2_BMC_CM_UART_RX";
72"FM_BMC_HEARTBEAT_N";
73"FM_ADR_MODE_SEL_R";
74"FM_XRC_READY_N";
75"SMB_HOST_STBY_LVC3_SCL_R1";
76"SMB_HOST_STBY_LVC3_SDA_R1";
77"SMB_PMBUS_BMC_STBY_LVC3_SDA_R1";
78"IRQ_SML0_ALERT_N";
79"PU_PCH_TLS_ENABLE_STRAP";
80"SMB_PMBUS_BMC_STBY_LVC3_SCL_R1";
81"FM_PASSWORD_CLEAR_N";
82"FM_CPU1_RC_EN";
83"FM_BOARD_REV_ID2";
84"FM_BOARD_REV_ID1";
85"IRQ_BMC_PCH_SCI_LPC_N";
86"FM_PWR_LED_N";
87"FM_ME_RECOVER_N";
88"FM_CPU_BMC_INIT";
89"FM_UART_PRES_N";
90"LPC_LAD0_IO0";
91"LPC_LAD2_IO2";
92"CLK_24M_BMC_LPC_R";
93"IRQ_PIRQA_SPI_TPM_N";
94"VID_PCH_CORE_PVNN_AUX_VID_0";
95"VID_PCH_CORE_PVNN_AUX_VID_1";
96"IRQ_LPC_SERIRQ_N";
97"RST_PLTRST_N";
98"FM_GLOBAL_RST_WARN_N";
99"FM_UART_ALERT_N";
100"RST_SYSTEM_BTN_N";
101"FP_NMI_BTN_N";
102"PU_IRQ_PCH_SCI_WHEA_N";
103"IRQ_PVDDQ_GHJ_VRHOT_LVT3_N";
104"IRQ_PVDDQ_KLM_VRHOT_LVT3_N";
105"IRQ_PVDDQ_ABC_VRHOT_LVT3_N";
106"IRQ_PVDDQ_DEF_VRHOT_LVT3_N";
107"FM_MB_SLOT_ID0";
108"FM_MB_SLOT_ID1";
109"PU_LPC_CLKRUN_N";
110"IRQ_VM_INT_N";
111"LPC_LAD_IO<3:0>";
112"CLK_24M_BMC_LPC";
%"LBG_CORE_QAT_EXT_D"
"6","(-4200,3200)","0","mstr_u_proc","I115";
;
CDS_SEC"6"
ROOM"SB"
BOM_COST"SB"
SEC_TYPE"BGA1"
PACK_TYPE"BGA1"
CDS_LOCATION"U7C1"
SEC"6"
CDS_LIB"mstr_u_proc"
LOCATION"U7C1"
MATERIAL"IC"
PART_NUMBER"H91415-002";
"GPP_D9_SSATA_DEVSLP3"
$PN"BY42"62;
"GPP_D8"
$PN"BR38"63;
"GPP_D7"
$PN"CA45"60;
"GPP_D6"
$PN"BW41"56;
"GPP_D5"
$PN"BM38"65;
"GPP_D4"
$PN"BM42"50;
"GPP_D3"
$PN"BW45"66;
"GPP_D23"
$PN"BN44"69;
"GPP_D22_IE_UART_TX"
$PN"BR46"70;
"GPP_D21_IE_UART_RX"
$PN"BV44"71;
"GPP_D20"
$PN"CA48"72;
"GPP_D2"
$PN"BJ44"67;
"GPP_D19"
$PN"CA43"73;
"GPP_D18"
$PN"CA41"74;
"GPP_D17"
$PN"BW48"68;
"GPP_D16_SML0BALERT_IE_N"
$PN"BV42"58;
"GPP_D15_SSATA_SDATAOUT0"
$PN"BW43"61;
"GPP_D14_SML0BDATA_IE"
$PN"BL44"53;
"GPP_D13_SML0BCLK_IE"
$PN"BY44"51;
"GPP_D12_SSATA_SDATAOUT1"
$PN"BN40"49;
"GPP_D11_SSATA_DEVSLP5"
$PN"BY47"59;
"GPP_D10_SSATA_DEVSLP4"
$PN"BV47"64;
"GPP_D1"
$PN"BK46"57;
"GPP_D0"
$PN"BR42"52;
"GPP_C9"
$PN"BY29"82;
"GPP_C8"
$PN"BW32"81;
"GPP_C7_SML1DATA_IE"
$PN"BV35"77;
"GPP_C6_SML1CLK_IE"
$PN"CA28"80;
"GPP_C5_SML0ALERT_IE_N"
$PN"BW34"78;
"GPP_C4_SML0DATA_IE"
$PN"BW30"27;
"GPP_C3_SML0CLK_IE"
$PN"BV29"28;
"GPP_C2_SMBALERT_N"
$PN"BY27"79;
"GPP_C23"
$PN"CA37"39;
"GPP_C22"
$PN"CA34"43;
"GPP_C21"
$PN"BY33"24;
"GPP_C20"
$PN"CA39"40;
"GPP_C1_SMBDATA"
$PN"BV27"76;
"GPP_C19"
$PN"BW39"41;
"GPP_C18"
$PN"BY35"42;
"GPP_C17"
$PN"BY31"23;
"GPP_C16"
$PN"BW37"25;
"GPP_C15"
$PN"CA32"55;
"GPP_C14"
$PN"BY38"85;
"GPP_C13"
$PN"BV38"84;
"GPP_C12"
$PN"CA30"54;
"GPP_C11"
$PN"BV33"83;
"GPP_C10"
$PN"BV31"26;
"GPP_C0_SMBCLK"
$PN"BW28"75;
"GPP_B9_SRCCLKREQ4_N"
$PN"BH20"8;
"GPP_B8_SRCCLKREQ3_N"
$PN"BN11"101;
"GPP_B7_SRCCLKREQ2_N"
$PN"BR13"104;
"GPP_B6_SRCCLKREQ1_N"
$PN"BG18"103;
"GPP_B5_SRCCLKREQ0_N"
$PN"BK17"106;
"GPP_B4_CPU_GP3"
$PN"BN7"105;
"GPP_B3_CPU_GP2"
$PN"BR9"7;
"GPP_B23_MEIE_SML1ALRT_N_PHOT_N"
$PN"BM20"34;
"GPP_B22"
$PN"BR17"16;
"GPP_B21"
$PN"BH17"15;
"GPP_B20"
$PN"BJ22"14;
"GPP_B2"
$PN"BN15"36;
"GPP_B1_CORE_VID1"
$PN"BH9"95;
"GPP_B19"
$PN"BK20"13;
"GPP_B18"
$PN"BL15"12;
"GPP_B17"
$PN"BG15"11;
"GPP_B16"
$PN"BG22"35;
"GPP_B15"
$PN"BK13"99;
"GPP_B14_SPKR"
$PN"BH13"10;
"GPP_B13_PLTRST_N"
$PN"BN18"97;
"GPP_B12_GLB_RST_WARN_N"
$PN"BL18"98;
"GPP_B11"
$PN"BK9"9;
"GPP_B10_SRCCLKREQ5_N"
$PN"BL11"100;
"GPP_B0_CORE_VID0"
$PN"BL7"94;
"GPP_A9_CLKOUT_LPC0_ESPI_CLK"
$PN"R3"92;
"GPP_A8_CLKRUN_N"
$PN"AB1"109;
"GPP_A7_PIRQA_N_ESPI_ALERT0_N"
$PN"AA2"93;
"GPP_A6_SERIRQ_ESPI_CS1_N"
$PN"P2"96;
"GPP_A5_LFRAME_N_ESPI_CS0_N"
$PN"P4"33;
"GPP_A4_LAD3_ESPI_IO3"
$PN"Y1"19;
"GPP_A3_LAD2_ESPI_IO2"
$PN"W2"91;
"GPP_A2_LAD1_ESPI_IO1"
$PN"N1"18;
"GPP_A23"
$PN"V1"22;
"GPP_A22"
$PN"AE4"29;
"GPP_A21"
$PN"AE2"30;
"GPP_A20"
$PN"W4"31;
"GPP_A1_LAD0_ESPI_IO0"
$PN"Y3"90;
"GPP_A19"
$PN"V3"87;
"GPP_A18"
$PN"AD3"32;
"GPP_A17"
$PN"AD1"88;
"GPP_A16_CLKOUT_LPC2"
$PN"T2"89;
"GPP_A15_SUSACK_N"
$PN"AC4"21;
"GPP_A14_ESPI_RESET_N"
$PN"AB3"108;
"GPP_A13_SUSWARN_N_SUSPWRDNACK"
$PN"T4"107;
"GPP_A12_BMBUSY_N_SXEXITHLDOFF_N"
$PN"R1"102;
"GPP_A11_PME_N"
$PN"AC2"20;
"GPP_A10_CLKOUT_LPC1"
$PN"AA4"110;
"GPP_A0_RCIN_N_ESPI_ALERT1_N"
$PN"N3"17;
%"TAP"
"6","(-6975,3300)","0","mstr_standard","I120";
;
HDL_TAP"TRUE"
CDS_LIB"mstr_standard"
BODY_TYPE"PLUMBING";
"B \NAC \NWC"111;
"S \NAC"
BN"0"90;
%"TAP"
"6","(-6975,3350)","0","mstr_standard","I121";
;
HDL_TAP"TRUE"
CDS_LIB"mstr_standard"
BODY_TYPE"PLUMBING";
"B \NAC \NWC"111;
"S \NAC"
BN"1"18;
%"TAP"
"6","(-6975,3400)","0","mstr_standard","I122";
;
HDL_TAP"TRUE"
CDS_LIB"mstr_standard"
BODY_TYPE"PLUMBING";
"B \NAC \NWC"111;
"S \NAC"
BN"2"91;
%"TAP"
"6","(-6975,3450)","0","mstr_standard","I123";
;
HDL_TAP"TRUE"
CDS_LIB"mstr_standard"
BODY_TYPE"PLUMBING";
"B \NAC \NWC"111;
"S \NAC"
BN"3"19;
%"RES"
"1","(-1450,2200)","0","mstr_discrete","I172";
;
CDS_SEC"1"
ROOM"CPLD"
SEC_TYPE"0402"
SEC"1"
CDS_LIB"mstr_discrete"
CDS_LOCATION"R2M3"
PART_NUMBER"G21796-074"
PACK_TYPE"0402"
MATERIAL"CHIP"
LOCATION"R2M3"
WATTAGE"1/16W"
TOLERANCE"1%"
VALUE"33.2";
"B"
$PN"2"44;
"A"
$PN"1"50;
%"RES"
"1","(-1550,4400)","0","mstr_discrete","I173";
;
CDS_SEC"1"
SEC"1"
SEC_TYPE"0402"
ROOM"CPLD"
CDS_LOCATION"R2N1"
CDS_LIB"mstr_discrete"
MATERIAL"CHIP"
PART_NUMBER"G21796-074"
PACK_TYPE"0402"
VALUE"33.2"
LOCATION"R2N1"
WATTAGE"1/16W"
TOLERANCE"1%";
"B"
$PN"2"37;
"A"
$PN"1"39;
%"RES"
"1","(-1475,2950)","0","mstr_discrete","I174";
;
CDS_SEC"1"
ROOM"CPLD"
SEC"1"
SEC_TYPE"0402"
CDS_LIB"mstr_discrete"
CDS_LOCATION"R2M7"
PART_NUMBER"G21796-074"
PACK_TYPE"0402"
LOCATION"R2M7"
MATERIAL"CHIP"
WATTAGE"1/16W"
TOLERANCE"1%"
VALUE"33.2";
"B"
$PN"2"45;
"A"
$PN"1"73;
%"FET_N_DUAL"
"5","(-2525,775)","0","mstr_discrete","I175";
;
CDS_SEC"1"
CDS_LOCATION"Q9A2"
ROOM"SB"
SEC_TYPE"SMLF"
BOM_COST"SB"
SEC"1"
CDS_LIB"mstr_discrete"
PACK_TYPE"SMLF"
PART_NUMBER"E40049-001"
MATERIAL"FET"
VALUE"NTJD4001N"
LOCATION"Q9A2";
"GATE <SIZE -1..0>"
$PN"2"86;
"SOURCE <SIZE-1..0>"
$PN"1"4;
"DRAIN <SIZE -1..0>"
$PN"6"48;
%"P3V3_STBY"
"1","(-500,1750)","0","mstr_symbols","I177";
;
SIZE"1B"
CDS_LIB"mstr_symbols"
BODY_TYPE"PLUMBING"
VOLTAGE"3.3V"
HDL_POWER"P3V3_STBY";
"G\NAC"1;
%"RES"
"1","(-700,1575)","0","mstr_discrete","I178";
;
CDS_SEC"1"
SEC"1"
BOM_COST"SB"
SEC_TYPE"0402"
CDS_LIB"mstr_discrete"
CDS_LOCATION"R9A20"
ROOM"SB"
PACK_TYPE"0402"
PART_NUMBER"G21796-271"
LOCATION"R9A20"
WATTAGE"1/16W"
MATERIAL"CHIP"
TOLERANCE"1.0%"
VALUE"221";
"B"
$PN"2"1;
"A"
$PN"1"46;
%"LED"
"3","(-1350,1575)","0","mstr_discrete","I179";
;
CDS_SEC"1"
SEC"1"
ROOM"SB"
PACK_TYPE"A1LF"
SEC_TYPE"A1LF"
BOM_COST"SB"
CDS_LOCATION"DS9A5"
CDS_LIB"mstr_discrete"
LOCATION"DS9A5"
MATERIAL"IC"
COLOR"GREEN"
PART_NUMBER"C97278-010";
"A"
$PN"1"46;
"C"
$PN"2"47;
%"FET_N_DUAL"
"5","(-1750,1250)","0","mstr_discrete","I180";
;
CDS_SEC"2"
BOM_COST"SB"
SEC_TYPE"SMLF"
SEC"2"
ROOM"SB"
CDS_LIB"mstr_discrete"
CDS_LOCATION"Q9A2"
PACK_TYPE"SMLF"
MATERIAL"FET"
VALUE"NTJD4001N"
PART_NUMBER"E40049-001"
LOCATION"Q9A2";
"GATE <SIZE -1..0>"
$PN"5"48;
"SOURCE <SIZE-1..0>"
$PN"4"2;
"DRAIN <SIZE -1..0>"
$PN"3"47;
%"GND"
"1","(-1750,900)","0","mstr_symbols","I181";
;
HDL_POWER"GND"
VOLTAGE"0.0V"
CDS_LIB"mstr_symbols"
SIZE"1B"
BODY_TYPE"PLUMBING";
"A\NAC"2;
%"P3V3_STBY"
"1","(-2525,1600)","0","mstr_symbols","I182";
;
SIZE"1B"
CDS_LIB"mstr_symbols"
BODY_TYPE"PLUMBING"
VOLTAGE"3.3V"
HDL_POWER"P3V3_STBY";
"G\NAC"3;
%"RES"
"2","(-2525,1400)","0","mstr_discrete","I183";
;
CDS_SEC"1"
ROOM"SB"
SEC"1"
BOM_COST"SB"
SEC_TYPE"0402"
CDS_LOCATION"R9A18"
CDS_LIB"mstr_discrete"
LOCATION"R9A18"
PART_NUMBER"G21796-072"
TOLERANCE"1%"
VALUE"4.75K"
MATERIAL"CHIP"
WATTAGE"1/16W"
PACK_TYPE"0402";
"A"
$PN"1"3;
"B"
$PN"2"48;
%"GND"
"1","(-2525,475)","0","mstr_symbols","I184";
;
HDL_POWER"GND"
CDS_LIB"mstr_symbols"
SIZE"1B"
BODY_TYPE"PLUMBING"
VOLTAGE"0.0V";
"A\NAC"4;
%"P3V3_STBY"
"1","(-2975,1200)","0","mstr_symbols","I185";
;
SIZE"1B"
BODY_TYPE"PLUMBING"
CDS_LIB"mstr_symbols"
VOLTAGE"3.3V"
HDL_POWER"P3V3_STBY";
"G\NAC"5;
%"RES"
"2","(-2975,950)","0","mstr_discrete","I186";
;
CDS_SEC"1"
BOM_COST"SB"
ROOM"SB"
CDS_LOCATION"R9A21"
SEC"1"
SEC_TYPE"0402"
CDS_LIB"mstr_discrete"
VALUE"4.75K"
LOCATION"R9A21"
WATTAGE"1/16W"
PART_NUMBER"G21796-072"
TOLERANCE"1%"
PACK_TYPE"0402"
MATERIAL"CHIP";
"A"
$PN"1"5;
"B"
$PN"2"86;
%"RES"
"1","(-6750,3700)","0","mstr_discrete","I189";
;
CDS_SEC"1"
ROOM"SYS_CLOCK"
SEC_TYPE"0402"
SEC"1"
BOM_COST"SM_CONTROLLER"
CDS_LIB"mstr_discrete"
CDS_LOCATION"R7C26"
TOLERANCE"1%"
MATERIAL"CHIP"
PACK_TYPE"0402"
PART_NUMBER"G21796-074"
WATTAGE"1/16W"
LOCATION"R7C26"
VALUE"33.2";
"B"
$PN"2"92;
"A"
$PN"1"112;
%"RES"
"2","(-1700,4725)","0","mstr_discrete","I213";
;
CDS_SEC"1"
CDS_LOCATION"R2U48"
SEC"1"
SEC_TYPE"0402"
CDS_LIB"mstr_discrete"
WATTAGE"1/16W"
VALUE"4.75K"
PART_NUMBER"G21796-072"
LOCATION"R2U48"
TOLERANCE"1%"
MATERIAL"CHIP"
PACK_TYPE"0402";
"A"
$PN"1"6;
"B"
$PN"2"23;
%"P3V3_STBY"
"1","(-1700,4900)","0","mstr_symbols","I214";
;
CDS_LIB"mstr_symbols"
SIZE"1B"
BODY_TYPE"PLUMBING"
VOLTAGE"3.3V"
HDL_POWER"P3V3_STBY";
"G\NAC"6;
%"RES"
"1","(-1425,4100)","0","mstr_discrete","I215";
;
CDS_SEC"1"
CDS_LOCATION"R2U50"
SEC"1"
SEC_TYPE"0402"
CDS_LIB"mstr_discrete"
PART_NUMBER"G21497-005"
LOCATION"R2U50"
PACK_TYPE"0402"
MATERIAL"EMPTY"
TOLERANCE"5%"
VALUE"0.0"
WATTAGE"1/16W";
"B"
$PN"2"38;
"A"
$PN"1"23;
END.
